(kicad_pcb
	(version 20260206)
	(generator "pcbnew")
	(generator_version "10.0")
	(general
		(thickness 1.6)
		(legacy_teardrops no)
	)
	(paper "A4")
	(title_block
		(title "v1-chassis-manager — T6M_CM_d_v01_1031_1645.brd")
		(comment 1 "Open CloudServer (Microsoft) / footprints 457-465 of 2512")
	)
	(layers
		(0 "F.Cu" signal "TOP")
		(4 "In1.Cu" signal "GND1")
		(6 "In2.Cu" signal "IN1")
		(8 "In3.Cu" signal "VCC1")
		(10 "In4.Cu" signal "VCC2")
		(12 "In5.Cu" signal "GND2")
		(14 "In6.Cu" signal "IN2")
		(16 "In7.Cu" signal "IN3")
		(18 "In8.Cu" signal "GND3")
		(2 "B.Cu" signal "BOTTOM")
		(9 "F.Adhes" user "F.Adhesive")
		(11 "B.Adhes" user "B.Adhesive")
		(13 "F.Paste" user "Package Geometry/Pastemask Top")
		(15 "B.Paste" user "Package Geometry/Pastemask Bottom")
		(5 "F.SilkS" user "Ref Des/Silkscreen Top")
		(7 "B.SilkS" user "Ref Des/Silkscreen Bottom")
		(1 "F.Mask" user "Board Geometry/Soldermask Top")
		(3 "B.Mask" user "Board Geometry/Soldermask Bottom")
		(17 "Dwgs.User" user "User.Drawings")
		(19 "Cmts.User" user "User.Comments")
		(21 "Eco1.User" user "User.Eco1")
		(23 "Eco2.User" user "User.Eco2")
		(25 "Edge.Cuts" user "Board Geometry/Outline")
		(27 "Margin" user)
		(31 "F.CrtYd" user "Package Geometry/Place Bound Top")
		(29 "B.CrtYd" user "Package Geometry/Place Bound Bottom")
		(35 "F.Fab" user "Ref Des/Assembly Top")
		(33 "B.Fab" user "Ref Des/Assembly Bottom")
	)
	(footprint ""
		(layer "F.Cu")
		(at 87.10676 -185.205624 90)
		(property "Reference" "C714"
			(at 4.198112 -2.117598 90)
			(unlocked yes)
			(layer "F.SilkS")
			(effects
				(font
					(size 0.7874 0.5842)
					(thickness 0.1524)
				)
				(justify left)
			)
		)
		(property "Value" ""
			(at 0 0 90)
			(layer "F.Fab")
			(effects
				(font
					(size 1.27 1.27)
				)
			)
		)
		(duplicate_pad_numbers_are_jumpers no)
		(fp_line
			(start 0.7874 -0.4064)
			(end 0.7874 0.4064)
			(stroke
				(width 0.1524)
				(type default)
			)
			(layer "F.SilkS")
		)
		(fp_line
			(start -0.7874 -0.4064)
			(end 0.7874 -0.4064)
			(stroke
				(width 0.1524)
				(type default)
			)
			(layer "F.SilkS")
		)
		(fp_line
			(start 0 0.381)
			(end 0 -0.381)
			(stroke
				(width 0.1524)
				(type default)
			)
			(layer "F.SilkS")
		)
		(fp_line
			(start 0.7874 0.4064)
			(end -0.7874 0.4064)
			(stroke
				(width 0.1524)
				(type default)
			)
			(layer "F.SilkS")
		)
		(fp_line
			(start -0.7874 0.4064)
			(end -0.7874 -0.4064)
			(stroke
				(width 0.1524)
				(type default)
			)
			(layer "F.SilkS")
		)
		(fp_poly
			(pts
				(xy -0.5334 0.254) (xy -0.635 0.254) (xy -0.635 0.2286) (xy -0.635 -0.254) (xy -0.5334 -0.254) (xy -0.5334 -0.2794)
				(xy 0.5334 -0.2794) (xy 0.5334 -0.254) (xy 0.635 -0.254) (xy 0.635 0.254) (xy 0.5334 0.254) (xy 0.5334 0.2794)
				(xy -0.508 0.2794) (xy -0.5334 0.2794)
			)
			(stroke
				(width 0)
				(type default)
			)
			(fill no)
			(layer "F.CrtYd")
		)
		(pad "1" smd rect
			(at 0.40005 0 90)
			(size 0.4572 0.508)
			(layers "F.Cu" "F.Mask" "F.Paste")
			(net "UART_T6_NODE4_RXD")
		)
		(pad "2" smd rect
			(at -0.40005 0 90)
			(size 0.4572 0.508)
			(layers "F.Cu" "F.Mask" "F.Paste")
			(net "GND")
		)
	)
	(footprint ""
		(layer "F.Cu")
		(at 105.191814 -108.92282 180)
		(property "Reference" "PC106"
			(at 5.833872 0.162052 0)
			(unlocked yes)
			(layer "F.SilkS")
			(effects
				(font
					(size 0.7874 0.5842)
					(thickness 0.1524)
				)
				(justify left)
			)
		)
		(property "Value" ""
			(at 0 0 180)
			(layer "F.Fab")
			(effects
				(font
					(size 1.27 1.27)
				)
			)
		)
		(duplicate_pad_numbers_are_jumpers no)
		(fp_line
			(start 1.905 0.8636)
			(end -1.905 0.8636)
			(stroke
				(width 0.1524)
				(type default)
			)
			(layer "F.SilkS")
		)
		(fp_line
			(start 1.905 -0.8636)
			(end 1.905 0.8636)
			(stroke
				(width 0.1524)
				(type default)
			)
			(layer "F.SilkS")
		)
		(fp_line
			(start 0 0.8382)
			(end 0 -0.8382)
			(stroke
				(width 0.1524)
				(type default)
			)
			(layer "F.SilkS")
		)
		(fp_line
			(start -1.905 0.8636)
			(end -1.905 -0.8636)
			(stroke
				(width 0.1524)
				(type default)
			)
			(layer "F.SilkS")
		)
		(fp_line
			(start -1.905 -0.8636)
			(end 1.905 -0.8636)
			(stroke
				(width 0.1524)
				(type default)
			)
			(layer "F.SilkS")
		)
		(fp_rect
			(start -1.524 0.7366)
			(end 1.524 -0.7366)
			(stroke
				(width 0)
				(type default)
			)
			(fill no)
			(layer "F.CrtYd")
		)
		(pad "1" smd rect
			(at 0.94996 0 180)
			(size 1.1176 1.3716)
			(layers "F.Cu" "F.Mask" "F.Paste")
			(net "GND")
		)
		(pad "2" smd rect
			(at -0.94996 0 180)
			(size 1.1176 1.3716)
			(layers "F.Cu" "F.Mask" "F.Paste")
			(net "PV_VCCP_NODE1")
		)
	)
	(footprint ""
		(layer "F.Cu")
		(at 169.643552 -57.99709)
		(property "Reference" "R268"
			(at -6.518148 0.01524 0)
			(unlocked yes)
			(layer "F.SilkS")
			(effects
				(font
					(size 0.7874 0.5842)
					(thickness 0.1524)
				)
				(justify left)
			)
		)
		(property "Value" ""
			(at 0 0 0)
			(layer "F.Fab")
			(effects
				(font
					(size 1.27 1.27)
				)
			)
		)
		(duplicate_pad_numbers_are_jumpers no)
		(fp_line
			(start -0.7874 -0.4064)
			(end 0.7874 -0.4064)
			(stroke
				(width 0.1524)
				(type default)
			)
			(layer "F.SilkS")
		)
		(fp_line
			(start -0.7874 0.4064)
			(end -0.7874 -0.4064)
			(stroke
				(width 0.1524)
				(type default)
			)
			(layer "F.SilkS")
		)
		(fp_line
			(start 0.7874 -0.4064)
			(end 0.7874 0.4064)
			(stroke
				(width 0.1524)
				(type default)
			)
			(layer "F.SilkS")
		)
		(fp_line
			(start 0.7874 0.4064)
			(end -0.7874 0.4064)
			(stroke
				(width 0.1524)
				(type default)
			)
			(layer "F.SilkS")
		)
		(fp_poly
			(pts
				(xy -0.508 0.2794) (xy -0.508 0.2286) (xy -0.635 0.2286) (xy -0.635 -0.254) (xy -0.5334 -0.254)
				(xy -0.5334 -0.2794) (xy 0.5334 -0.2794) (xy 0.5334 -0.254) (xy 0.635 -0.254) (xy 0.635 0.254) (xy 0.5334 0.254)
				(xy 0.5334 0.2794)
			)
			(stroke
				(width 0)
				(type default)
			)
			(fill no)
			(layer "F.CrtYd")
		)
		(pad "1" smd rect
			(at 0.40005 0)
			(size 0.4572 0.508)
			(layers "F.Cu" "F.Mask" "F.Paste")
			(net "USB2_L_DP")
		)
		(pad "2" smd rect
			(at -0.40005 0)
			(size 0.4572 0.508)
			(layers "F.Cu" "F.Mask" "F.Paste")
			(net "USB2_DP")
		)
	)
	(footprint ""
		(layer "F.Cu")
		(at 120.252744 -159.500316 -90)
		(property "Reference" "R645"
			(at 0.051816 1.878838 90)
			(unlocked yes)
			(layer "F.SilkS")
			(effects
				(font
					(size 0.635 0.4064)
					(thickness 0.1524)
				)
				(justify left)
			)
		)
		(property "Value" ""
			(at 0 0 270)
			(layer "F.Fab")
			(effects
				(font
					(size 1.27 1.27)
				)
			)
		)
		(duplicate_pad_numbers_are_jumpers no)
		(fp_line
			(start -0.7874 0.4064)
			(end -0.7874 -0.4064)
			(stroke
				(width 0.1524)
				(type default)
			)
			(layer "F.SilkS")
		)
		(fp_line
			(start 0.7874 0.4064)
			(end -0.7874 0.4064)
			(stroke
				(width 0.1524)
				(type default)
			)
			(layer "F.SilkS")
		)
		(fp_line
			(start -0.7874 -0.4064)
			(end 0.7874 -0.4064)
			(stroke
				(width 0.1524)
				(type default)
			)
			(layer "F.SilkS")
		)
		(fp_line
			(start 0.7874 -0.4064)
			(end 0.7874 0.4064)
			(stroke
				(width 0.1524)
				(type default)
			)
			(layer "F.SilkS")
		)
		(fp_poly
			(pts
				(xy -0.508 0.2794) (xy -0.508 0.2286) (xy -0.635 0.2286) (xy -0.635 -0.254) (xy -0.5334 -0.254)
				(xy -0.5334 -0.2794) (xy 0.5334 -0.2794) (xy 0.5334 -0.254) (xy 0.635 -0.254) (xy 0.635 0.254) (xy 0.5334 0.254)
				(xy 0.5334 0.2794)
			)
			(stroke
				(width 0)
				(type default)
			)
			(fill no)
			(layer "F.CrtYd")
		)
		(pad "1" smd rect
			(at 0.40005 0 270)
			(size 0.4572 0.508)
			(layers "F.Cu" "F.Mask" "F.Paste")
			(net "I2C_PSU2_SDA")
		)
		(pad "2" smd rect
			(at -0.40005 0 270)
			(size 0.4572 0.508)
			(layers "F.Cu" "F.Mask" "F.Paste")
			(net "I2C_PSU2_SDA_MOS")
		)
	)
	(footprint ""
		(layer "F.Cu")
		(at 85.601048 -128.998726 -90)
		(property "Reference" "R1254"
			(at 5.940044 4.649724 90)
			(unlocked yes)
			(layer "F.SilkS")
			(effects
				(font
					(size 0.7874 0.5842)
					(thickness 0.1524)
				)
				(justify left)
			)
		)
		(property "Value" ""
			(at 0 0 270)
			(layer "F.Fab")
			(effects
				(font
					(size 1.27 1.27)
				)
			)
		)
		(duplicate_pad_numbers_are_jumpers no)
		(fp_line
			(start -0.7874 0.4064)
			(end -0.7874 -0.4064)
			(stroke
				(width 0.1524)
				(type default)
			)
			(layer "F.SilkS")
		)
		(fp_line
			(start 0.7874 0.4064)
			(end -0.7874 0.4064)
			(stroke
				(width 0.1524)
				(type default)
			)
			(layer "F.SilkS")
		)
		(fp_line
			(start -0.7874 -0.4064)
			(end 0.7874 -0.4064)
			(stroke
				(width 0.1524)
				(type default)
			)
			(layer "F.SilkS")
		)
		(fp_line
			(start 0.7874 -0.4064)
			(end 0.7874 0.4064)
			(stroke
				(width 0.1524)
				(type default)
			)
			(layer "F.SilkS")
		)
		(fp_poly
			(pts
				(xy -0.508 0.2794) (xy -0.508 0.2286) (xy -0.635 0.2286) (xy -0.635 -0.254) (xy -0.5334 -0.254)
				(xy -0.5334 -0.2794) (xy 0.5334 -0.2794) (xy 0.5334 -0.254) (xy 0.635 -0.254) (xy 0.635 0.254) (xy 0.5334 0.254)
				(xy 0.5334 0.2794)
			)
			(stroke
				(width 0)
				(type default)
			)
			(fill no)
			(layer "F.CrtYd")
		)
		(pad "1" smd rect
			(at 0.40005 0 270)
			(size 0.4572 0.508)
			(layers "F.Cu" "F.Mask" "F.Paste")
			(net "PORT80_LOUT2")
		)
		(pad "2" smd rect
			(at -0.40005 0 270)
			(size 0.4572 0.508)
			(layers "F.Cu" "F.Mask" "F.Paste")
			(net "N53313479")
		)
	)
	(footprint ""
		(layer "F.Cu")
		(at 111.317532 -138.681206 90)
		(property "Reference" "PC87"
			(at 3.924554 3.960114 90)
			(unlocked yes)
			(layer "F.SilkS")
			(effects
				(font
					(size 0.635 0.4064)
					(thickness 0.1524)
				)
			)
		)
		(property "Value" ""
			(at 0 0 90)
			(layer "F.Fab")
			(effects
				(font
					(size 1.27 1.27)
				)
			)
		)
		(duplicate_pad_numbers_are_jumpers no)
		(fp_line
			(start 1.2954 -0.5842)
			(end 1.2954 0.5842)
			(stroke
				(width 0.1524)
				(type default)
			)
			(layer "F.SilkS")
		)
		(fp_line
			(start 0 -0.5842)
			(end 0 0.5842)
			(stroke
				(width 0.1524)
				(type default)
			)
			(layer "F.SilkS")
		)
		(fp_line
			(start -1.2954 -0.5842)
			(end 1.2954 -0.5842)
			(stroke
				(width 0.1524)
				(type default)
			)
			(layer "F.SilkS")
		)
		(fp_line
			(start 1.2954 0.5842)
			(end -1.2954 0.5842)
			(stroke
				(width 0.1524)
				(type default)
			)
			(layer "F.SilkS")
		)
		(fp_line
			(start -1.2954 0.5842)
			(end -1.2954 -0.5842)
			(stroke
				(width 0.1524)
				(type default)
			)
			(layer "F.SilkS")
		)
		(fp_poly
			(pts
				(xy 0.8636 -0.4572) (xy 0.8636 -0.3556) (xy 1.143 -0.3556) (xy 1.143 0.3556) (xy 0.8636 0.3556)
				(xy 0.8636 0.4572) (xy -0.8636 0.4572) (xy -0.8636 0.3556) (xy -1.143 0.3556) (xy -1.143 -0.3556)
				(xy -0.8636 -0.3556) (xy -0.8636 -0.4572)
			)
			(stroke
				(width 0)
				(type default)
			)
			(fill no)
			(layer "F.CrtYd")
		)
		(fp_line
			(start 0.884936 -0.504952)
			(end 0.884936 0.504952)
			(stroke
				(width 0.1)
				(type default)
			)
			(layer "F.Fab")
		)
		(fp_line
			(start -0.884936 -0.504952)
			(end 0.884936 -0.504952)
			(stroke
				(width 0.1)
				(type default)
			)
			(layer "F.Fab")
		)
		(fp_line
			(start 0.884936 0.504952)
			(end -0.884936 0.504952)
			(stroke
				(width 0.1)
				(type default)
			)
			(layer "F.Fab")
		)
		(fp_line
			(start -0.884936 0.504952)
			(end -0.884936 -0.504952)
			(stroke
				(width 0.1)
				(type default)
			)
			(layer "F.Fab")
		)
		(pad "1" smd rect
			(at 0.7366 0 180)
			(size 0.7112 0.8128)
			(layers "F.Cu" "F.Mask" "F.Paste")
			(net "VR_PVCCP_NODE1_VCC")
		)
		(pad "2" smd rect
			(at -0.7366 0 180)
			(size 0.7112 0.8128)
			(layers "F.Cu" "F.Mask" "F.Paste")
			(net "AGND_PVCCP_NODE1")
		)
	)
	(footprint ""
		(layer "F.Cu")
		(at 17.013174 -16.260572 -90)
		(property "Reference" "C544"
			(at 1.500124 6.13664 90)
			(unlocked yes)
			(layer "F.SilkS")
			(effects
				(font
					(size 0.7874 0.5842)
					(thickness 0.1524)
				)
				(justify left)
			)
		)
		(property "Value" ""
			(at 0 0 270)
			(layer "F.Fab")
			(effects
				(font
					(size 1.27 1.27)
				)
			)
		)
		(duplicate_pad_numbers_are_jumpers no)
		(fp_line
			(start -0.7874 0.4064)
			(end -0.7874 -0.4064)
			(stroke
				(width 0.1524)
				(type default)
			)
			(layer "F.SilkS")
		)
		(fp_line
			(start 0.7874 0.4064)
			(end -0.7874 0.4064)
			(stroke
				(width 0.1524)
				(type default)
			)
			(layer "F.SilkS")
		)
		(fp_line
			(start 0 0.381)
			(end 0 -0.381)
			(stroke
				(width 0.1524)
				(type default)
			)
			(layer "F.SilkS")
		)
		(fp_line
			(start -0.7874 -0.4064)
			(end 0.7874 -0.4064)
			(stroke
				(width 0.1524)
				(type default)
			)
			(layer "F.SilkS")
		)
		(fp_line
			(start 0.7874 -0.4064)
			(end 0.7874 0.4064)
			(stroke
				(width 0.1524)
				(type default)
			)
			(layer "F.SilkS")
		)
		(fp_poly
			(pts
				(xy -0.5334 0.254) (xy -0.635 0.254) (xy -0.635 0.2286) (xy -0.635 -0.254) (xy -0.5334 -0.254) (xy -0.5334 -0.2794)
				(xy 0.5334 -0.2794) (xy 0.5334 -0.254) (xy 0.635 -0.254) (xy 0.635 0.254) (xy 0.5334 0.254) (xy 0.5334 0.2794)
				(xy -0.508 0.2794) (xy -0.5334 0.2794)
			)
			(stroke
				(width 0)
				(type default)
			)
			(fill no)
			(layer "F.CrtYd")
		)
		(pad "1" smd rect
			(at 0.40005 0 270)
			(size 0.4572 0.508)
			(layers "F.Cu" "F.Mask" "F.Paste")
			(net "GND")
		)
		(pad "2" smd rect
			(at -0.40005 0 270)
			(size 0.4572 0.508)
			(layers "F.Cu" "F.Mask" "F.Paste")
			(net "N54251539")
		)
	)
	(footprint ""
		(layer "F.Cu")
		(at 161.200846 -33.589214)
		(property "Reference" "R656"
			(at -1.343152 -1.010412 0)
			(unlocked yes)
			(layer "F.SilkS")
			(effects
				(font
					(size 0.7874 0.5842)
					(thickness 0.1524)
				)
				(justify left)
			)
		)
		(property "Value" ""
			(at 0 0 0)
			(layer "F.Fab")
			(effects
				(font
					(size 1.27 1.27)
				)
			)
		)
		(duplicate_pad_numbers_are_jumpers no)
		(fp_line
			(start -0.7874 -0.4064)
			(end 0.7874 -0.4064)
			(stroke
				(width 0.1524)
				(type default)
			)
			(layer "F.SilkS")
		)
		(fp_line
			(start -0.7874 0.4064)
			(end -0.7874 -0.4064)
			(stroke
				(width 0.1524)
				(type default)
			)
			(layer "F.SilkS")
		)
		(fp_line
			(start 0.7874 -0.4064)
			(end 0.7874 0.4064)
			(stroke
				(width 0.1524)
				(type default)
			)
			(layer "F.SilkS")
		)
		(fp_line
			(start 0.7874 0.4064)
			(end -0.7874 0.4064)
			(stroke
				(width 0.1524)
				(type default)
			)
			(layer "F.SilkS")
		)
		(fp_poly
			(pts
				(xy -0.508 0.2794) (xy -0.508 0.2286) (xy -0.635 0.2286) (xy -0.635 -0.254) (xy -0.5334 -0.254)
				(xy -0.5334 -0.2794) (xy 0.5334 -0.2794) (xy 0.5334 -0.254) (xy 0.635 -0.254) (xy 0.635 0.254) (xy 0.5334 0.254)
				(xy 0.5334 0.2794)
			)
			(stroke
				(width 0)
				(type default)
			)
			(fill no)
			(layer "F.CrtYd")
		)
		(pad "1" smd rect
			(at 0.40005 0)
			(size 0.4572 0.508)
			(layers "F.Cu" "F.Mask" "F.Paste")
			(net "GND")
		)
		(pad "2" smd rect
			(at -0.40005 0)
			(size 0.4572 0.508)
			(layers "F.Cu" "F.Mask" "F.Paste")
			(net "N37284163")
		)
	)
	(footprint ""
		(layer "F.Cu")
		(at 55.14467 -173.527466 180)
		(property "Reference" "U89"
			(at 5.938266 -133.039612 90)
			(unlocked yes)
			(layer "F.SilkS")
			(effects
				(font
					(size 0.7874 0.5842)
					(thickness 0.1524)
				)
				(justify left)
			)
		)
		(property "Value" ""
			(at 0 0 180)
			(layer "F.Fab")
			(effects
				(font
					(size 1.27 1.27)
				)
			)
		)
		(duplicate_pad_numbers_are_jumpers no)
		(fp_line
			(start 1.549908 2.032)
			(end -1.549908 2.032)
			(stroke
				(width 0.1524)
				(type default)
			)
			(layer "F.SilkS")
		)
		(fp_line
			(start 1.549908 -2.032)
			(end 1.549908 2.032)
			(stroke
				(width 0.1524)
				(type default)
			)
			(layer "F.SilkS")
		)
		(fp_line
			(start -1.549908 2.032)
			(end -1.549908 -2.032)
			(stroke
				(width 0.1524)
				(type default)
			)
			(layer "F.SilkS")
		)
		(fp_line
			(start -1.549908 -2.032)
			(end 1.549908 -2.032)
			(stroke
				(width 0.1524)
				(type default)
			)
			(layer "F.SilkS")
		)
		(fp_poly
			(pts
				(xy -2.9464 1.016) (xy -2.9464 1.524) (xy -2.1844 1.27)
			)
			(stroke
				(width 0)
				(type default)
			)
			(fill yes)
			(layer "F.SilkS")
		)
		(fp_poly
			(pts
				(xy -1.549908 0.849884) (xy -1.2319 0.849884) (xy -1.2319 1.9431) (xy -1.1811 1.9431) (xy 1.1811 1.9431)
				(xy 1.2319 1.9431) (xy 1.2319 0.849884) (xy 1.549908 0.849884) (xy 1.549908 -0.849884) (xy 1.2319 -0.849884)
				(xy 1.2319 -1.9431) (xy 1.1811 -1.9431) (xy -1.1811 -1.9431) (xy -1.2319 -1.9431) (xy -1.2319 -0.849884)
				(xy -1.549908 -0.849884)
			)
			(stroke
				(width 0)
				(type default)
			)
			(fill no)
			(layer "F.CrtYd")
		)
		(fp_line
			(start 1.549908 0.849884)
			(end 1.549908 -0.849884)
			(stroke
				(width 0.1)
				(type default)
			)
			(layer "F.Fab")
		)
		(fp_line
			(start 1.549908 -0.849884)
			(end -1.549908 -0.849884)
			(stroke
				(width 0.1)
				(type default)
			)
			(layer "F.Fab")
		)
		(fp_line
			(start -1.549908 0.849884)
			(end 1.549908 0.849884)
			(stroke
				(width 0.1)
				(type default)
			)
			(layer "F.Fab")
		)
		(fp_line
			(start -1.549908 -0.849884)
			(end -1.549908 0.849884)
			(stroke
				(width 0.1)
				(type default)
			)
			(layer "F.Fab")
		)
		(fp_text user "3"
			(at 1.439418 2.684526 0)
			(unlocked yes)
			(layer "F.SilkS")
			(effects
				(font
					(size 0.635 0.4064)
					(thickness 0.1524)
				)
				(justify left)
			)
		)
		(fp_text user "4"
			(at 0.872998 -2.54508 0)
			(unlocked yes)
			(layer "F.SilkS")
			(effects
				(font
					(size 0.635 0.4064)
					(thickness 0.1524)
				)
				(justify left)
			)
		)
		(fp_text user "1"
			(at -0.541528 2.538222 0)
			(unlocked yes)
			(layer "F.SilkS")
			(effects
				(font
					(size 0.635 0.4064)
					(thickness 0.1524)
				)
				(justify left)
			)
		)
		(fp_text user "5"
			(at -1.881632 -2.664714 0)
			(unlocked yes)
			(layer "F.SilkS")
			(effects
				(font
					(size 0.635 0.4064)
					(thickness 0.1524)
				)
				(justify left)
			)
		)
		(pad "1" smd rect
			(at -0.94996 1.225042 180)
			(size 0.4572 1.3208)
			(layers "F.Cu" "F.Mask" "F.Paste")
			(net "Net_1710")
		)
		(pad "2" smd rect
			(at 0 1.225042 180)
			(size 0.4572 1.3208)
			(layers "F.Cu" "F.Mask" "F.Paste")
			(net "PSU4_DC_OK_R_BUF")
		)
		(pad "3" smd rect
			(at 0.94996 1.225042 180)
			(size 0.4572 1.3208)
			(layers "F.Cu" "F.Mask" "F.Paste")
			(net "GND")
		)
		(pad "4" smd rect
			(at 0.94996 -1.225042 180)
			(size 0.4572 1.3208)
			(layers "F.Cu" "F.Mask" "F.Paste")
			(net "PSU4_DC_OK")
		)
		(pad "5" smd rect
			(at -0.94996 -1.225042 180)
			(size 0.4572 1.3208)
			(layers "F.Cu" "F.Mask" "F.Paste")
			(net "P3V3_NODE1")
		)
	)
)
